# T6G (Grand Teton) — schematic netlist excerpt (pin names and nets, part order shuffled) for the footprints in the layout excerpt that follows; sources: Cadence DE-HDL packaged netlist, KiCad conversion of 04192023_DAF0TMB3IC0_F0TG_MB_C_brd_V02_OCP.brd

R864  Q_RES  1K 1% EMPTY  pkg 0201LF  page 342 : A = P1V8_CPU1_RT_1D ; B = RT_CPU1_P2_ADDR2
PR7  Q_RES  8.87K 1% EMPTY  pkg 0402LF  page 203 : A = PVDDCR_CPU1_P0_LSET6 ; B = GND
PC2207  Q_CAP  1UF 25V 10% X6S  pkg C0402  page 146 : A = P12V_AUX ; B = GND

(kicad_pcb
	(version 20260206)
	(generator "pcbnew")
	(generator_version "10.0")
	(general
		(thickness 1.6)
		(legacy_teardrops no)
	)
	(paper "A4")
	(title_block
		(title "04192023_DAF0TMB3IC0_F0TG_MB_C_brd_V02_OCP.brd")
		(comment 1 "Grand Teton / footprints 3619-3621 of 8354")
	)
	(layers
		(0 "F.Cu" signal "TOP")
		(4 "In1.Cu" signal "GND")
		(6 "In2.Cu" signal "IN1")
		(8 "In3.Cu" signal "GND1")
		(10 "In4.Cu" signal "IN2")
		(12 "In5.Cu" signal "GND2")
		(14 "In6.Cu" signal "IN3")
		(16 "In7.Cu" signal "GND3")
		(18 "In8.Cu" signal "VCC")
		(20 "In9.Cu" signal "VCC1")
		(22 "In10.Cu" signal "GND4")
		(24 "In11.Cu" signal "IN4")
		(26 "In12.Cu" signal "GND5")
		(28 "In13.Cu" signal "IN5")
		(30 "In14.Cu" signal "GND6")
		(32 "In15.Cu" signal "IN6")
		(34 "In16.Cu" signal "GND7")
		(2 "B.Cu" signal "BOTTOM")
		(9 "F.Adhes" user "F.Adhesive")
		(11 "B.Adhes" user "B.Adhesive")
		(13 "F.Paste" user "Package Geometry/Pastemask Top")
		(15 "B.Paste" user "Package Geometry/Pastemask Bottom")
		(5 "F.SilkS" user "Ref Des/Silkscreen Top")
		(7 "B.SilkS" user "Ref Des/Silkscreen Bottom")
		(1 "F.Mask" user "Board Geometry/Soldermask Top")
		(3 "B.Mask" user "Board Geometry/Soldermask Bottom")
		(17 "Dwgs.User" user "User.Drawings")
		(19 "Cmts.User" user "User.Comments")
		(21 "Eco1.User" user "User.Eco1")
		(23 "Eco2.User" user "User.Eco2")
		(25 "Edge.Cuts" user "Board Geometry/Outline")
		(27 "Margin" user)
		(31 "F.CrtYd" user "Package Geometry/Place Bound Top")
		(29 "B.CrtYd" user "Package Geometry/Place Bound Bottom")
		(35 "F.Fab" user "Ref Des/Assembly Top")
		(33 "B.Fab" user "Ref Des/Assembly Bottom")
	)
	(footprint ""
		(layer "F.Cu")
		(at 350.361504 -345.146122)
		(property "Reference" "PR7"
			(at 0 0 0)
			(layer "F.SilkS")
			(hide yes)
			(effects
				(font
					(size 1.27 1.27)
				)
			)
		)
		(property "Value" ""
			(at 0 0 0)
			(layer "F.Fab")
			(effects
				(font
					(size 1.27 1.27)
				)
			)
		)
		(duplicate_pad_numbers_are_jumpers no)
		(fp_line
			(start -0.7874 -0.4064)
			(end 0.7874 -0.4064)
			(stroke
				(width 0.1524)
				(type default)
			)
			(layer "F.SilkS")
		)
		(fp_line
			(start -0.7874 0.4064)
			(end -0.7874 -0.4064)
			(stroke
				(width 0.1524)
				(type default)
			)
			(layer "F.SilkS")
		)
		(fp_line
			(start 0.7874 -0.4064)
			(end 0.7874 0.4064)
			(stroke
				(width 0.1524)
				(type default)
			)
			(layer "F.SilkS")
		)
		(fp_line
			(start 0.7874 0.4064)
			(end -0.7874 0.4064)
			(stroke
				(width 0.1524)
				(type default)
			)
			(layer "F.SilkS")
		)
		(fp_line
			(start -0.67945 -0.305054)
			(end -0.12065 -0.305054)
			(stroke
				(width 0.1)
				(type default)
			)
			(layer "F.Fab")
		)
		(fp_line
			(start -0.67945 0.3048)
			(end -0.67945 -0.305054)
			(stroke
				(width 0.1)
				(type default)
			)
			(layer "F.Fab")
		)
		(fp_line
			(start -0.12065 -0.305054)
			(end -0.12065 -0.2794)
			(stroke
				(width 0.1)
				(type default)
			)
			(layer "F.Fab")
		)
		(fp_line
			(start -0.12065 -0.2794)
			(end 0.12065 -0.2794)
			(stroke
				(width 0.1)
				(type default)
			)
			(layer "F.Fab")
		)
		(fp_line
			(start -0.12065 0.2794)
			(end -0.12065 0.3048)
			(stroke
				(width 0.1)
				(type default)
			)
			(layer "F.Fab")
		)
		(fp_line
			(start -0.12065 0.3048)
			(end -0.67945 0.3048)
			(stroke
				(width 0.1)
				(type default)
			)
			(layer "F.Fab")
		)
		(fp_line
			(start 0.120396 0.2794)
			(end -0.12065 0.2794)
			(stroke
				(width 0.1)
				(type default)
			)
			(layer "F.Fab")
		)
		(fp_line
			(start 0.120396 0.3048)
			(end 0.120396 0.2794)
			(stroke
				(width 0.1)
				(type default)
			)
			(layer "F.Fab")
		)
		(fp_line
			(start 0.12065 -0.3048)
			(end 0.67945 -0.3048)
			(stroke
				(width 0.1)
				(type default)
			)
			(layer "F.Fab")
		)
		(fp_line
			(start 0.12065 -0.2794)
			(end 0.12065 -0.3048)
			(stroke
				(width 0.1)
				(type default)
			)
			(layer "F.Fab")
		)
		(fp_line
			(start 0.67945 -0.3048)
			(end 0.67945 0.3048)
			(stroke
				(width 0.1)
				(type default)
			)
			(layer "F.Fab")
		)
		(fp_line
			(start 0.67945 0.3048)
			(end 0.120396 0.3048)
			(stroke
				(width 0.1)
				(type default)
			)
			(layer "F.Fab")
		)
		(pad "1" smd circle
			(at -0.40005 0)
			(size 0 0)
			(layers "F.Cu" "F.Mask" "F.Paste")
			(net "PVDDCR_CPU1_P0_LSET6")
		)
		(pad "2" smd circle
			(at 0.40005 0)
			(size 0 0)
			(layers "F.Cu" "F.Mask" "F.Paste")
			(net "GND")
		)
	)
	(footprint ""
		(layer "F.Cu")
		(at 175.300894 -391.34288 180)
		(property "Reference" "R864"
			(at 0 0 180)
			(layer "F.SilkS")
			(hide yes)
			(effects
				(font
					(size 1.27 1.27)
				)
			)
		)
		(property "Value" ""
			(at 0 0 180)
			(layer "F.Fab")
			(effects
				(font
					(size 1.27 1.27)
				)
			)
		)
		(duplicate_pad_numbers_are_jumpers no)
		(fp_line
			(start 0.32512 0.175006)
			(end -0.32512 0.175006)
			(stroke
				(width 0.1)
				(type default)
			)
			(layer "F.Fab")
		)
		(fp_line
			(start 0.32512 -0.175006)
			(end 0.32512 0.175006)
			(stroke
				(width 0.1)
				(type default)
			)
			(layer "F.Fab")
		)
		(fp_line
			(start -0.32512 0.175006)
			(end -0.32512 -0.175006)
			(stroke
				(width 0.1)
				(type default)
			)
			(layer "F.Fab")
		)
		(fp_line
			(start -0.32512 -0.175006)
			(end 0.32512 -0.175006)
			(stroke
				(width 0.1)
				(type default)
			)
			(layer "F.Fab")
		)
		(pad "1" smd rect
			(at -0.2667 0 180)
			(size 0.3048 0.381)
			(layers "F.Cu" "F.Mask" "F.Paste")
			(net "P1V8_CPU1_RT_1D")
		)
		(pad "2" smd rect
			(at 0.2667 0)
			(size 0.3048 0.381)
			(layers "F.Cu" "F.Mask" "F.Paste")
			(net "RT_CPU1_P2_ADDR2")
		)
	)
	(footprint ""
		(layer "F.Cu")
		(at 256.889504 -44.520612 180)
		(property "Reference" "PC2207"
			(at 0 0 180)
			(layer "F.SilkS")
			(hide yes)
			(effects
				(font
					(size 1.27 1.27)
				)
			)
		)
		(property "Value" ""
			(at 0 0 180)
			(layer "F.Fab")
			(effects
				(font
					(size 1.27 1.27)
				)
			)
		)
		(duplicate_pad_numbers_are_jumpers no)
		(fp_line
			(start 0.7874 0.4064)
			(end -0.7874 0.4064)
			(stroke
				(width 0.1524)
				(type default)
			)
			(layer "F.SilkS")
		)
		(fp_line
			(start 0.7874 -0.4064)
			(end 0.7874 0.4064)
			(stroke
				(width 0.1524)
				(type default)
			)
			(layer "F.SilkS")
		)
		(fp_line
			(start -0.7874 0.4064)
			(end -0.7874 -0.4064)
			(stroke
				(width 0.1524)
				(type default)
			)
			(layer "F.SilkS")
		)
		(fp_line
			(start -0.7874 -0.4064)
			(end 0.7874 -0.4064)
			(stroke
				(width 0.1524)
				(type default)
			)
			(layer "F.SilkS")
		)
		(fp_line
			(start 0.67945 0.3048)
			(end 0.120396 0.3048)
			(stroke
				(width 0.1)
				(type default)
			)
			(layer "F.Fab")
		)
		(fp_line
			(start 0.67945 -0.3048)
			(end 0.67945 0.3048)
			(stroke
				(width 0.1)
				(type default)
			)
			(layer "F.Fab")
		)
		(fp_line
			(start 0.12065 -0.2794)
			(end 0.12065 -0.3048)
			(stroke
				(width 0.1)
				(type default)
			)
			(layer "F.Fab")
		)
		(fp_line
			(start 0.12065 -0.3048)
			(end 0.67945 -0.3048)
			(stroke
				(width 0.1)
				(type default)
			)
			(layer "F.Fab")
		)
		(fp_line
			(start 0.120396 0.3048)
			(end 0.120396 0.2794)
			(stroke
				(width 0.1)
				(type default)
			)
			(layer "F.Fab")
		)
		(fp_line
			(start 0.120396 0.2794)
			(end -0.12065 0.2794)
			(stroke
				(width 0.1)
				(type default)
			)
			(layer "F.Fab")
		)
		(fp_line
			(start -0.12065 0.3048)
			(end -0.67945 0.3048)
			(stroke
				(width 0.1)
				(type default)
			)
			(layer "F.Fab")
		)
		(fp_line
			(start -0.12065 0.2794)
			(end -0.12065 0.3048)
			(stroke
				(width 0.1)
				(type default)
			)
			(layer "F.Fab")
		)
		(fp_line
			(start -0.12065 -0.2794)
			(end 0.12065 -0.2794)
			(stroke
				(width 0.1)
				(type default)
			)
			(layer "F.Fab")
		)
		(fp_line
			(start -0.12065 -0.305054)
			(end -0.12065 -0.2794)
			(stroke
				(width 0.1)
				(type default)
			)
			(layer "F.Fab")
		)
		(fp_line
			(start -0.67945 0.3048)
			(end -0.67945 -0.305054)
			(stroke
				(width 0.1)
				(type default)
			)
			(layer "F.Fab")
		)
		(fp_line
			(start -0.67945 -0.305054)
			(end -0.12065 -0.305054)
			(stroke
				(width 0.1)
				(type default)
			)
			(layer "F.Fab")
		)
		(pad "1" smd circle
			(at -0.40005 0 180)
			(size 0 0)
			(layers "F.Cu" "F.Mask" "F.Paste")
			(net "P12V_AUX")
		)
		(pad "2" smd circle
			(at 0.40005 0 180)
			(size 0 0)
			(layers "F.Cu" "F.Mask" "F.Paste")
			(net "GND")
		)
	)
)
